# TIMECARD (Time Appliance Project (Time Card)) — schematic netlist excerpt (pin names and nets, part order shuffled) for the footprints in the layout excerpt that follows; sources: Cadence DE-HDL packaged netlist, KiCad conversion of R4006-B0001-02_R01.brd

C67  CAPACITOR  0.1UF 10V 10%  pkg SMC_0402R_H022  page 21 : \1\ = XP3R3V_FPGA ; \2\ = SG
C68  CAPACITOR  0.1UF 25V 10%  pkg SMC_0402R_H022  page 21 : \1\ = XP3R3V_FPGA ; \2\ = SG

(kicad_pcb
	(version 20260206)
	(generator "pcbnew")
	(generator_version "10.0")
	(general
		(thickness 1.6)
		(legacy_teardrops no)
	)
	(paper "A4")
	(title_block
		(title "timecard-production-celestica-r4006 — R4006-B0001-02_R01.brd")
		(comment 1 "Time Appliance Project (Time Card) / footprints 1106-1107 of 1113")
	)
	(layers
		(0 "F.Cu" signal "TOP")
		(4 "In1.Cu" signal "L02_GND1")
		(6 "In2.Cu" signal "L03_SIG1")
		(8 "In3.Cu" signal "L04_GND2")
		(10 "In4.Cu" signal "L05_VCC1")
		(12 "In5.Cu" signal "L06_VCC2")
		(14 "In6.Cu" signal "L07_GND3")
		(16 "In7.Cu" signal "L08_SIG2")
		(18 "In8.Cu" signal "L09_GND4")
		(2 "B.Cu" signal "BOTTOM")
		(9 "F.Adhes" user "F.Adhesive")
		(11 "B.Adhes" user "B.Adhesive")
		(13 "F.Paste" user "Package Geometry/Pastemask Top")
		(15 "B.Paste" user "Package Geometry/Pastemask Bottom")
		(5 "F.SilkS" user "Ref Des/Silkscreen Top")
		(7 "B.SilkS" user "Ref Des/Silkscreen Bottom")
		(1 "F.Mask" user "Board Geometry/Soldermask Top")
		(3 "B.Mask" user "Board Geometry/Soldermask Bottom")
		(17 "Dwgs.User" user "User.Drawings")
		(19 "Cmts.User" user "User.Comments")
		(21 "Eco1.User" user "User.Eco1")
		(23 "Eco2.User" user "User.Eco2")
		(25 "Edge.Cuts" user "Board Geometry/Outline")
		(27 "Margin" user)
		(31 "F.CrtYd" user "Package Geometry/Place Bound Top")
		(29 "B.CrtYd" user "Package Geometry/Place Bound Bottom")
		(35 "F.Fab" user "Ref Des/Assembly Top")
		(33 "B.Fab" user "Ref Des/Assembly Bottom")
	)
	(footprint ""
		(layer "B.Cu")
		(at 89.027 -45.974 90)
		(property "Reference" "C67"
			(at -0.381 -1.56337 270)
			(unlocked yes)
			(layer "B.SilkS")
			(effects
				(font
					(size 0.7874 0.5842)
					(thickness 0.1524)
				)
				(justify mirror)
			)
		)
		(property "Value" "VAL*"
			(at -0.0762 2.067306 90)
			(unlocked yes)
			(layer "B.Fab")
			(hide yes)
			(effects
				(font
					(size 0.7874 0.5842)
					(thickness 0.1524)
				)
				(justify mirror)
			)
		)
		(property "Device Type" "CAPACITOR-G105-0B104-CK,0.1UF,A"
			(at -0.0508 1.127506 90)
			(unlocked yes)
			(layer "B.Fab")
			(hide yes)
			(effects
				(font
					(size 0.7874 0.5842)
					(thickness 0.1524)
				)
				(justify mirror)
			)
		)
		(property "User Part Number" "PARTNUM*"
			(at -0.1016 4.023106 90)
			(unlocked yes)
			(layer "Cmts.User")
			(hide yes)
			(effects
				(font
					(size 0.7874 0.5842)
					(thickness 0.1524)
				)
				(justify mirror)
			)
		)
		(property "Tolerance" "TOL*"
			(at -0.0762 3.032506 90)
			(unlocked yes)
			(layer "Cmts.User")
			(hide yes)
			(effects
				(font
					(size 0.7874 0.5842)
					(thickness 0.1524)
				)
				(justify mirror)
			)
		)
		(duplicate_pad_numbers_are_jumpers no)
		(fp_line
			(start 1.143 -0.5588)
			(end 1.143 0.5588)
			(stroke
				(width 0.1)
				(type default)
			)
			(layer "B.SilkS")
		)
		(fp_line
			(start -1.143 -0.5588)
			(end 1.143 -0.5588)
			(stroke
				(width 0.1)
				(type default)
			)
			(layer "B.SilkS")
		)
		(fp_line
			(start 1.143 0.5588)
			(end -1.143 0.5588)
			(stroke
				(width 0.1)
				(type default)
			)
			(layer "B.SilkS")
		)
		(fp_line
			(start -1.143 0.5588)
			(end -1.143 -0.5588)
			(stroke
				(width 0.1)
				(type default)
			)
			(layer "B.SilkS")
		)
		(fp_rect
			(start -1.143 0.5588)
			(end 1.143 -0.5588)
			(stroke
				(width 0)
				(type default)
			)
			(fill no)
			(layer "B.CrtYd")
		)
		(fp_line
			(start 0.508 -0.3048)
			(end 0.508 0.3048)
			(stroke
				(width 0.1)
				(type default)
			)
			(layer "B.Fab")
		)
		(fp_line
			(start -0.508 -0.3048)
			(end 0.508 -0.3048)
			(stroke
				(width 0.1)
				(type default)
			)
			(layer "B.Fab")
		)
		(fp_line
			(start 0.508 0.3048)
			(end -0.508 0.3048)
			(stroke
				(width 0.1)
				(type default)
			)
			(layer "B.Fab")
		)
		(fp_line
			(start -0.508 0.3048)
			(end -0.508 -0.3048)
			(stroke
				(width 0.1)
				(type default)
			)
			(layer "B.Fab")
		)
		(pad "1" smd rect
			(at 0.5334 0 270)
			(size 0.7112 0.6096)
			(layers "B.Cu" "B.Mask" "B.Paste")
			(net "XP3R3V_FPGA")
		)
		(pad "2" smd rect
			(at -0.5334 0 270)
			(size 0.7112 0.6096)
			(layers "B.Cu" "B.Mask" "B.Paste")
			(net "SG")
		)
		(zone
			(layer "B.Cu")
			(hatch none 0.5)
			(connect_pads
				(clearance 0)
			)
			(min_thickness 0.25)
			(keepout
				(tracks allowed)
				(vias not_allowed)
				(pads allowed)
				(copperpour not_allowed)
				(footprints allowed)
			)
			(placement
				(enabled no)
				(sheetname "")
			)
			(fill
				(thermal_gap 0.5)
				(thermal_bridge_width 0.5)
				(island_removal_mode 0)
			)
			(polygon
				(pts
					(xy 89.3318 -45.8978) (xy 89.3318 -46.0502) (xy 88.7222 -46.0502) (xy 88.7222 -45.8978)
				)
			)
		)
	)
	(footprint ""
		(layer "B.Cu")
		(at 61.976 -59.817)
		(property "Reference" "C68"
			(at -2.54 0.03937 0)
			(unlocked yes)
			(layer "B.SilkS")
			(effects
				(font
					(size 0.7874 0.5842)
					(thickness 0.1524)
				)
				(justify mirror)
			)
		)
		(property "Value" "VAL*"
			(at -0.0762 2.067306 0)
			(unlocked yes)
			(layer "B.Fab")
			(hide yes)
			(effects
				(font
					(size 0.7874 0.5842)
					(thickness 0.1524)
				)
				(justify mirror)
			)
		)
		(property "Device Type" "CAPACITOR-G105-0B104-EK,0.1UF,A"
			(at -0.0508 1.127506 0)
			(unlocked yes)
			(layer "B.Fab")
			(hide yes)
			(effects
				(font
					(size 0.7874 0.5842)
					(thickness 0.1524)
				)
				(justify mirror)
			)
		)
		(property "User Part Number" "PARTNUM*"
			(at -0.1016 4.023106 0)
			(unlocked yes)
			(layer "Cmts.User")
			(hide yes)
			(effects
				(font
					(size 0.7874 0.5842)
					(thickness 0.1524)
				)
				(justify mirror)
			)
		)
		(property "Tolerance" "TOL*"
			(at -0.0762 3.032506 0)
			(unlocked yes)
			(layer "Cmts.User")
			(hide yes)
			(effects
				(font
					(size 0.7874 0.5842)
					(thickness 0.1524)
				)
				(justify mirror)
			)
		)
		(duplicate_pad_numbers_are_jumpers no)
		(fp_line
			(start -1.143 -0.5588)
			(end 1.143 -0.5588)
			(stroke
				(width 0.1)
				(type default)
			)
			(layer "B.SilkS")
		)
		(fp_line
			(start -1.143 0.5588)
			(end -1.143 -0.5588)
			(stroke
				(width 0.1)
				(type default)
			)
			(layer "B.SilkS")
		)
		(fp_line
			(start 1.143 -0.5588)
			(end 1.143 0.5588)
			(stroke
				(width 0.1)
				(type default)
			)
			(layer "B.SilkS")
		)
		(fp_line
			(start 1.143 0.5588)
			(end -1.143 0.5588)
			(stroke
				(width 0.1)
				(type default)
			)
			(layer "B.SilkS")
		)
		(fp_rect
			(start -1.143 -0.5588)
			(end 1.143 0.5588)
			(stroke
				(width 0)
				(type default)
			)
			(fill no)
			(layer "B.CrtYd")
		)
		(fp_line
			(start -0.508 -0.3048)
			(end 0.508 -0.3048)
			(stroke
				(width 0.1)
				(type default)
			)
			(layer "B.Fab")
		)
		(fp_line
			(start -0.508 0.3048)
			(end -0.508 -0.3048)
			(stroke
				(width 0.1)
				(type default)
			)
			(layer "B.Fab")
		)
		(fp_line
			(start 0.508 -0.3048)
			(end 0.508 0.3048)
			(stroke
				(width 0.1)
				(type default)
			)
			(layer "B.Fab")
		)
		(fp_line
			(start 0.508 0.3048)
			(end -0.508 0.3048)
			(stroke
				(width 0.1)
				(type default)
			)
			(layer "B.Fab")
		)
		(pad "1" smd rect
			(at 0.5334 0 180)
			(size 0.7112 0.6096)
			(layers "B.Cu" "B.Mask" "B.Paste")
			(net "XP3R3V_FPGA")
		)
		(pad "2" smd rect
			(at -0.5334 0 180)
			(size 0.7112 0.6096)
			(layers "B.Cu" "B.Mask" "B.Paste")
			(net "SG")
		)
		(zone
			(layer "B.Cu")
			(hatch none 0.5)
			(connect_pads
				(clearance 0)
			)
			(min_thickness 0.25)
			(keepout
				(tracks allowed)
				(vias not_allowed)
				(pads allowed)
				(copperpour not_allowed)
				(footprints allowed)
			)
			(placement
				(enabled no)
				(sheetname "")
			)
			(fill
				(thermal_gap 0.5)
				(thermal_bridge_width 0.5)
				(island_removal_mode 0)
			)
			(polygon
				(pts
					(xy 61.8998 -60.1218) (xy 61.8998 -59.5122) (xy 62.0522 -59.5122) (xy 62.0522 -60.1218)
				)
			)
		)
		(zone
			(layer "B.Cu")
			(hatch none 0.5)
			(connect_pads
				(clearance 0)
			)
			(min_thickness 0.25)
			(keepout
				(tracks not_allowed)
				(vias allowed)
				(pads allowed)
				(copperpour not_allowed)
				(footprints allowed)
			)
			(placement
				(enabled no)
				(sheetname "")
			)
			(fill
				(thermal_gap 0.5)
				(thermal_bridge_width 0.5)
				(island_removal_mode 0)
			)
			(polygon
				(pts
					(xy 61.8998 -60.1218) (xy 61.8998 -59.5122) (xy 62.0522 -59.5122) (xy 62.0522 -60.1218)
				)
			)
		)
	)
)
